# T6G (Grand Teton) — schematic netlist excerpt (pin names and nets, part order shuffled) for the footprints in the layout excerpt that follows; sources: Cadence DE-HDL packaged netlist, KiCad conversion of 04192023_DAF0TMB3IC0_F0TG_MB_C_brd_V02_OCP.brd

C6645  Q_CAP_DIFFBUS  DIFF BUS_0.22UF 6.3V 20% X6S  pkg C0201  page 319 : \1\ = P5E_CPU1_P0_TX_BUF_C_DP<8> ; \2\ = P5E_CPU1_P0_TX_BUF_DP<8>
R6861  Q_RES  1K 1% CHIP  pkg 0402LF  page 364 : A = P1V8_AUX ; B = PWRGD_P0V9_RETIMER_CPU1_R

(kicad_pcb
	(version 20260206)
	(generator "pcbnew")
	(generator_version "10.0")
	(general
		(thickness 1.6)
		(legacy_teardrops no)
	)
	(paper "A4")
	(title_block
		(title "04192023_DAF0TMB3IC0_F0TG_MB_C_brd_V02_OCP.brd")
		(comment 1 "Grand Teton / footprints 4052-4053 of 8354")
	)
	(layers
		(0 "F.Cu" signal "TOP")
		(4 "In1.Cu" signal "GND")
		(6 "In2.Cu" signal "IN1")
		(8 "In3.Cu" signal "GND1")
		(10 "In4.Cu" signal "IN2")
		(12 "In5.Cu" signal "GND2")
		(14 "In6.Cu" signal "IN3")
		(16 "In7.Cu" signal "GND3")
		(18 "In8.Cu" signal "VCC")
		(20 "In9.Cu" signal "VCC1")
		(22 "In10.Cu" signal "GND4")
		(24 "In11.Cu" signal "IN4")
		(26 "In12.Cu" signal "GND5")
		(28 "In13.Cu" signal "IN5")
		(30 "In14.Cu" signal "GND6")
		(32 "In15.Cu" signal "IN6")
		(34 "In16.Cu" signal "GND7")
		(2 "B.Cu" signal "BOTTOM")
		(9 "F.Adhes" user "F.Adhesive")
		(11 "B.Adhes" user "B.Adhesive")
		(13 "F.Paste" user "Package Geometry/Pastemask Top")
		(15 "B.Paste" user "Package Geometry/Pastemask Bottom")
		(5 "F.SilkS" user "Ref Des/Silkscreen Top")
		(7 "B.SilkS" user "Ref Des/Silkscreen Bottom")
		(1 "F.Mask" user "Board Geometry/Soldermask Top")
		(3 "B.Mask" user "Board Geometry/Soldermask Bottom")
		(17 "Dwgs.User" user "User.Drawings")
		(19 "Cmts.User" user "User.Comments")
		(21 "Eco1.User" user "User.Eco1")
		(23 "Eco2.User" user "User.Eco2")
		(25 "Edge.Cuts" user "Board Geometry/Outline")
		(27 "Margin" user)
		(31 "F.CrtYd" user "Package Geometry/Place Bound Top")
		(29 "B.CrtYd" user "Package Geometry/Place Bound Bottom")
		(35 "F.Fab" user "Ref Des/Assembly Top")
		(33 "B.Fab" user "Ref Des/Assembly Bottom")
	)
	(footprint ""
		(layer "F.Cu")
		(at 20.575524 -405.868378 90)
		(property "Reference" "R6861"
			(at 0 0 90)
			(layer "F.SilkS")
			(hide yes)
			(effects
				(font
					(size 1.27 1.27)
				)
			)
		)
		(property "Value" ""
			(at 0 0 90)
			(layer "F.Fab")
			(effects
				(font
					(size 1.27 1.27)
				)
			)
		)
		(duplicate_pad_numbers_are_jumpers no)
		(fp_line
			(start 0.7874 -0.4064)
			(end 0.7874 0.4064)
			(stroke
				(width 0.1524)
				(type default)
			)
			(layer "F.SilkS")
		)
		(fp_line
			(start -0.7874 -0.4064)
			(end 0.7874 -0.4064)
			(stroke
				(width 0.1524)
				(type default)
			)
			(layer "F.SilkS")
		)
		(fp_line
			(start 0.7874 0.4064)
			(end -0.7874 0.4064)
			(stroke
				(width 0.1524)
				(type default)
			)
			(layer "F.SilkS")
		)
		(fp_line
			(start -0.7874 0.4064)
			(end -0.7874 -0.4064)
			(stroke
				(width 0.1524)
				(type default)
			)
			(layer "F.SilkS")
		)
		(fp_line
			(start -0.12065 -0.305054)
			(end -0.12065 -0.2794)
			(stroke
				(width 0.1)
				(type default)
			)
			(layer "F.Fab")
		)
		(fp_line
			(start -0.67945 -0.305054)
			(end -0.12065 -0.305054)
			(stroke
				(width 0.1)
				(type default)
			)
			(layer "F.Fab")
		)
		(fp_line
			(start 0.67945 -0.3048)
			(end 0.67945 0.3048)
			(stroke
				(width 0.1)
				(type default)
			)
			(layer "F.Fab")
		)
		(fp_line
			(start 0.12065 -0.3048)
			(end 0.67945 -0.3048)
			(stroke
				(width 0.1)
				(type default)
			)
			(layer "F.Fab")
		)
		(fp_line
			(start 0.12065 -0.2794)
			(end 0.12065 -0.3048)
			(stroke
				(width 0.1)
				(type default)
			)
			(layer "F.Fab")
		)
		(fp_line
			(start -0.12065 -0.2794)
			(end 0.12065 -0.2794)
			(stroke
				(width 0.1)
				(type default)
			)
			(layer "F.Fab")
		)
		(fp_line
			(start 0.120396 0.2794)
			(end -0.12065 0.2794)
			(stroke
				(width 0.1)
				(type default)
			)
			(layer "F.Fab")
		)
		(fp_line
			(start -0.12065 0.2794)
			(end -0.12065 0.3048)
			(stroke
				(width 0.1)
				(type default)
			)
			(layer "F.Fab")
		)
		(fp_line
			(start 0.67945 0.3048)
			(end 0.120396 0.3048)
			(stroke
				(width 0.1)
				(type default)
			)
			(layer "F.Fab")
		)
		(fp_line
			(start 0.120396 0.3048)
			(end 0.120396 0.2794)
			(stroke
				(width 0.1)
				(type default)
			)
			(layer "F.Fab")
		)
		(fp_line
			(start -0.12065 0.3048)
			(end -0.67945 0.3048)
			(stroke
				(width 0.1)
				(type default)
			)
			(layer "F.Fab")
		)
		(fp_line
			(start -0.67945 0.3048)
			(end -0.67945 -0.305054)
			(stroke
				(width 0.1)
				(type default)
			)
			(layer "F.Fab")
		)
		(pad "1" smd circle
			(at -0.40005 0 90)
			(size 0 0)
			(layers "F.Cu" "F.Mask" "F.Paste")
			(net "P1V8_AUX")
		)
		(pad "2" smd circle
			(at 0.40005 0 90)
			(size 0 0)
			(layers "F.Cu" "F.Mask" "F.Paste")
			(net "PWRGD_P0V9_RETIMER_CPU1_R")
		)
	)
	(footprint ""
		(layer "F.Cu")
		(at 73.189084 -408.517344 -90)
		(property "Reference" "C6645"
			(at 0 0 270)
			(layer "F.SilkS")
			(hide yes)
			(effects
				(font
					(size 1.27 1.27)
				)
			)
		)
		(property "Value" ""
			(at 0 0 270)
			(layer "F.Fab")
			(effects
				(font
					(size 1.27 1.27)
				)
			)
		)
		(duplicate_pad_numbers_are_jumpers no)
		(fp_line
			(start -0.299974 0.150114)
			(end -0.299974 -0.150114)
			(stroke
				(width 0.1)
				(type default)
			)
			(layer "F.Fab")
		)
		(fp_line
			(start 0.299974 0.150114)
			(end -0.299974 0.150114)
			(stroke
				(width 0.1)
				(type default)
			)
			(layer "F.Fab")
		)
		(fp_line
			(start -0.299974 -0.150114)
			(end 0.299974 -0.150114)
			(stroke
				(width 0.1)
				(type default)
			)
			(layer "F.Fab")
		)
		(fp_line
			(start 0.299974 -0.150114)
			(end 0.299974 0.150114)
			(stroke
				(width 0.1)
				(type default)
			)
			(layer "F.Fab")
		)
		(pad "1" smd rect
			(at -0.2667 0 270)
			(size 0.3048 0.381)
			(layers "F.Cu" "F.Mask" "F.Paste")
			(net "P5E_CPU1_P0_TX_BUF_C_DP<8>")
		)
		(pad "2" smd rect
			(at 0.2667 0 270)
			(size 0.3048 0.381)
			(layers "F.Cu" "F.Mask" "F.Paste")
			(net "P5E_CPU1_P0_TX_BUF_DP<8>")
		)
	)
)
